(kicad_pcb
	(version 20260206)
	(generator "pcbnew")
	(generator_version "10.0")
	(general
		(thickness 1.6)
		(legacy_teardrops no)
	)
	(paper "A4")
	(title_block
		(title "Wiwynn_Tioga_Pass_MB.brd")
		(comment 1 "Tioga Pass / footprints 4739-4746 of 4770")
	)
	(layers
		(0 "F.Cu" signal "TOP")
		(4 "In1.Cu" signal "L2GND")
		(6 "In2.Cu" signal "L3")
		(8 "In3.Cu" signal "L4GND")
		(10 "In4.Cu" signal "L5")
		(12 "In5.Cu" signal "L6GND")
		(14 "In6.Cu" signal "L7VCC")
		(16 "In7.Cu" signal "L8VCC")
		(18 "In8.Cu" signal "L9GND")
		(20 "In9.Cu" signal "L10")
		(22 "In10.Cu" signal "L11GND")
		(24 "In11.Cu" signal "L12")
		(26 "In12.Cu" signal "L13GND")
		(2 "B.Cu" signal "BOTTOM")
		(9 "F.Adhes" user "F.Adhesive")
		(11 "B.Adhes" user "B.Adhesive")
		(13 "F.Paste" user "Package Geometry/Pastemask Top")
		(15 "B.Paste" user "Package Geometry/Pastemask Bottom")
		(5 "F.SilkS" user "Ref Des/Silkscreen Top")
		(7 "B.SilkS" user "Ref Des/Silkscreen Bottom")
		(1 "F.Mask" user "Board Geometry/Soldermask Top")
		(3 "B.Mask" user "Board Geometry/Soldermask Bottom")
		(17 "Dwgs.User" user "User.Drawings")
		(19 "Cmts.User" user "User.Comments")
		(21 "Eco1.User" user "User.Eco1")
		(23 "Eco2.User" user "User.Eco2")
		(25 "Edge.Cuts" user "Board Geometry/Outline")
		(27 "Margin" user)
		(31 "F.CrtYd" user "Package Geometry/Place Bound Top")
		(29 "B.CrtYd" user "Package Geometry/Place Bound Bottom")
		(35 "F.Fab" user "Ref Des/Assembly Top")
		(33 "B.Fab" user "Ref Des/Assembly Bottom")
	)
	(footprint ""
		(layer "B.Cu")
		(at 494.3729 -124.0663 180)
		(property "Reference" "R1M12"
			(at 0 0 0)
			(layer "B.SilkS")
			(hide yes)
			(effects
				(font
					(size 1.27 1.27)
				)
				(justify mirror)
			)
		)
		(property "Value" ""
			(at 0 0 0)
			(layer "B.Fab")
			(effects
				(font
					(size 1.27 1.27)
				)
				(justify mirror)
			)
		)
		(duplicate_pad_numbers_are_jumpers no)
		(fp_poly
			(pts
				(xy 0.2794 -0.1016) (xy -0.2794 -0.1016) (xy -0.2794 0.9906) (xy 0.2794 0.9906)
			)
			(stroke
				(width 0)
				(type default)
			)
			(fill no)
			(layer "B.CrtYd")
		)
		(fp_line
			(start 0.2794 0.9906)
			(end -0.2794 0.9906)
			(stroke
				(width 0.1)
				(type default)
			)
			(layer "B.Fab")
		)
		(fp_line
			(start 0.2794 -0.1016)
			(end 0.2794 0.9906)
			(stroke
				(width 0.1)
				(type default)
			)
			(layer "B.Fab")
		)
		(fp_line
			(start -0.2794 0.9906)
			(end -0.2794 -0.1016)
			(stroke
				(width 0.1)
				(type default)
			)
			(layer "B.Fab")
		)
		(fp_line
			(start -0.2794 -0.1016)
			(end 0.2794 -0.1016)
			(stroke
				(width 0.1)
				(type default)
			)
			(layer "B.Fab")
		)
		(pad "1" smd rect
			(at 0 0)
			(size 0.508 0.508)
			(layers "B.Cu" "B.Mask" "B.Paste")
			(net "P3V3")
		)
		(pad "2" smd rect
			(at 0 0.889)
			(size 0.508 0.508)
			(layers "B.Cu" "B.Mask" "B.Paste")
			(net "LED_SAS_ACT_R_N")
		)
		(zone
			(layer "B.Cu")
			(hatch none 0.5)
			(connect_pads
				(clearance 0)
			)
			(min_thickness 0.25)
			(keepout
				(tracks not_allowed)
				(vias allowed)
				(pads allowed)
				(copperpour not_allowed)
				(footprints allowed)
			)
			(placement
				(enabled no)
				(sheetname "")
			)
			(fill
				(thermal_gap 0.5)
				(thermal_bridge_width 0.5)
				(island_removal_mode 0)
			)
			(polygon
				(pts
					(xy 494.1189 -124.7013) (xy 494.6269 -124.7013) (xy 494.6269 -124.3203) (xy 494.1189 -124.3203)
				)
			)
		)
		(zone
			(layer "B.Cu")
			(hatch none 0.5)
			(connect_pads
				(clearance 0)
			)
			(min_thickness 0.25)
			(keepout
				(tracks allowed)
				(vias not_allowed)
				(pads allowed)
				(copperpour not_allowed)
				(footprints allowed)
			)
			(placement
				(enabled no)
				(sheetname "")
			)
			(fill
				(thermal_gap 0.5)
				(thermal_bridge_width 0.5)
				(island_removal_mode 0)
			)
			(polygon
				(pts
					(xy 494.1189 -124.3203) (xy 494.6269 -124.3203) (xy 494.6269 -124.7013) (xy 494.1189 -124.7013)
				)
			)
		)
	)
	(footprint ""
		(layer "B.Cu")
		(at 463.677 -4.5085)
		(property "Reference" "C2U23"
			(at 0 0 0)
			(layer "B.SilkS")
			(hide yes)
			(effects
				(font
					(size 1.27 1.27)
				)
				(justify mirror)
			)
		)
		(property "Value" ""
			(at 0 0 0)
			(layer "B.Fab")
			(effects
				(font
					(size 1.27 1.27)
				)
				(justify mirror)
			)
		)
		(duplicate_pad_numbers_are_jumpers no)
		(fp_poly
			(pts
				(xy -0.3048 -0.1016) (xy -0.3048 0.9906) (xy 0.3048 0.9906) (xy 0.3048 -0.1016)
			)
			(stroke
				(width 0)
				(type default)
			)
			(fill no)
			(layer "B.CrtYd")
		)
		(fp_line
			(start -0.3048 -0.1016)
			(end 0.3048 -0.1016)
			(stroke
				(width 0.1)
				(type default)
			)
			(layer "B.Fab")
		)
		(fp_line
			(start -0.3048 0.9906)
			(end -0.3048 -0.1016)
			(stroke
				(width 0.1)
				(type default)
			)
			(layer "B.Fab")
		)
		(fp_line
			(start 0.3048 -0.1016)
			(end 0.3048 0.9906)
			(stroke
				(width 0.1)
				(type default)
			)
			(layer "B.Fab")
		)
		(fp_line
			(start 0.3048 0.9906)
			(end -0.3048 0.9906)
			(stroke
				(width 0.1)
				(type default)
			)
			(layer "B.Fab")
		)
		(pad "1" smd rect
			(at 0 0 180)
			(size 0.508 0.508)
			(layers "B.Cu" "B.Mask" "B.Paste")
			(net "P3V3_STBY")
		)
		(pad "2" smd rect
			(at 0 0.889 180)
			(size 0.508 0.508)
			(layers "B.Cu" "B.Mask" "B.Paste")
			(net "GND")
		)
		(zone
			(layer "B.Cu")
			(hatch none 0.5)
			(connect_pads
				(clearance 0)
			)
			(min_thickness 0.25)
			(keepout
				(tracks allowed)
				(vias not_allowed)
				(pads allowed)
				(copperpour not_allowed)
				(footprints allowed)
			)
			(placement
				(enabled no)
				(sheetname "")
			)
			(fill
				(thermal_gap 0.5)
				(thermal_bridge_width 0.5)
				(island_removal_mode 0)
			)
			(polygon
				(pts
					(xy 463.931 -4.2545) (xy 463.423 -4.2545) (xy 463.423 -3.8735) (xy 463.931 -3.8735)
				)
			)
		)
		(zone
			(layer "B.Cu")
			(hatch none 0.5)
			(connect_pads
				(clearance 0)
			)
			(min_thickness 0.25)
			(keepout
				(tracks not_allowed)
				(vias allowed)
				(pads allowed)
				(copperpour not_allowed)
				(footprints allowed)
			)
			(placement
				(enabled no)
				(sheetname "")
			)
			(fill
				(thermal_gap 0.5)
				(thermal_bridge_width 0.5)
				(island_removal_mode 0)
			)
			(polygon
				(pts
					(xy 463.931 -3.8735) (xy 463.423 -3.8735) (xy 463.423 -4.2545) (xy 463.931 -4.2545)
				)
			)
		)
	)
	(footprint ""
		(layer "B.Cu")
		(at 1.3462 -149.987 90)
		(property "Reference" "C9L5"
			(at 0 0 90)
			(layer "B.SilkS")
			(hide yes)
			(effects
				(font
					(size 1.27 1.27)
				)
				(justify mirror)
			)
		)
		(property "Value" ""
			(at 0 0 90)
			(layer "B.Fab")
			(effects
				(font
					(size 1.27 1.27)
				)
				(justify mirror)
			)
		)
		(duplicate_pad_numbers_are_jumpers no)
		(fp_rect
			(start -0.7239 -0.2159)
			(end 0.7239 1.9939)
			(stroke
				(width 0)
				(type default)
			)
			(fill no)
			(layer "B.CrtYd")
		)
		(fp_line
			(start 0.7239 -0.2159)
			(end 0.7239 1.9939)
			(stroke
				(width 0.1)
				(type default)
			)
			(layer "B.Fab")
		)
		(fp_line
			(start -0.7239 -0.2159)
			(end 0.7239 -0.2159)
			(stroke
				(width 0.1)
				(type default)
			)
			(layer "B.Fab")
		)
		(fp_line
			(start 0.7239 1.9939)
			(end -0.7239 1.9939)
			(stroke
				(width 0.1)
				(type default)
			)
			(layer "B.Fab")
		)
		(fp_line
			(start -0.7239 1.9939)
			(end -0.7239 -0.2159)
			(stroke
				(width 0.1)
				(type default)
			)
			(layer "B.Fab")
		)
		(pad "1" smd rect
			(at 0 0 270)
			(size 1.27 1.016)
			(layers "B.Cu" "B.Mask" "B.Paste")
			(net "VR_FET_SW_P12V_STBY_PVDDQ_KLM")
		)
		(pad "2" smd rect
			(at 0 1.778 270)
			(size 1.27 1.016)
			(layers "B.Cu" "B.Mask" "B.Paste")
			(net "GND")
		)
		(zone
			(layer "B.Cu")
			(hatch none 0.5)
			(connect_pads
				(clearance 0)
			)
			(min_thickness 0.25)
			(keepout
				(tracks not_allowed)
				(vias allowed)
				(pads allowed)
				(copperpour not_allowed)
				(footprints allowed)
			)
			(placement
				(enabled no)
				(sheetname "")
			)
			(fill
				(thermal_gap 0.5)
				(thermal_bridge_width 0.5)
				(island_removal_mode 0)
			)
			(polygon
				(pts
					(xy 1.8542 -149.352) (xy 2.6162 -149.352) (xy 2.6162 -150.622) (xy 1.8542 -150.622)
				)
			)
		)
	)
	(footprint ""
		(layer "B.Cu")
		(at 197.239128 -78.915006 90)
		(property "Reference" "R6P10"
			(at 0 0 90)
			(layer "B.SilkS")
			(hide yes)
			(effects
				(font
					(size 1.27 1.27)
				)
				(justify mirror)
			)
		)
		(property "Value" ""
			(at 0 0 90)
			(layer "B.Fab")
			(effects
				(font
					(size 1.27 1.27)
				)
				(justify mirror)
			)
		)
		(duplicate_pad_numbers_are_jumpers no)
		(fp_rect
			(start 0.2794 -0.1016)
			(end -0.2794 0.9906)
			(stroke
				(width 0)
				(type default)
			)
			(fill no)
			(layer "B.CrtYd")
		)
		(fp_line
			(start 0.2794 -0.1016)
			(end 0.2794 0.9906)
			(stroke
				(width 0.1)
				(type default)
			)
			(layer "B.Fab")
		)
		(fp_line
			(start -0.2794 -0.1016)
			(end 0.2794 -0.1016)
			(stroke
				(width 0.1)
				(type default)
			)
			(layer "B.Fab")
		)
		(fp_line
			(start 0.2794 0.9906)
			(end -0.2794 0.9906)
			(stroke
				(width 0.1)
				(type default)
			)
			(layer "B.Fab")
		)
		(fp_line
			(start -0.2794 0.9906)
			(end -0.2794 -0.1016)
			(stroke
				(width 0.1)
				(type default)
			)
			(layer "B.Fab")
		)
		(pad "1" smd rect
			(at 0 0 270)
			(size 0.508 0.508)
			(layers "B.Cu" "B.Mask" "B.Paste")
			(net "VR_PVCCIN_CPU0_PH4_VCIN")
		)
		(pad "2" smd rect
			(at 0 0.889 270)
			(size 0.508 0.508)
			(layers "B.Cu" "B.Mask" "B.Paste")
			(net "P5V_STBY")
		)
		(zone
			(layer "B.Cu")
			(hatch none 0.5)
			(connect_pads
				(clearance 0)
			)
			(min_thickness 0.25)
			(keepout
				(tracks allowed)
				(vias not_allowed)
				(pads allowed)
				(copperpour not_allowed)
				(footprints allowed)
			)
			(placement
				(enabled no)
				(sheetname "")
			)
			(fill
				(thermal_gap 0.5)
				(thermal_bridge_width 0.5)
				(island_removal_mode 0)
			)
			(polygon
				(pts
					(xy 197.493128 -79.169006) (xy 197.493128 -78.661006) (xy 197.874128 -78.661006) (xy 197.874128 -79.169006)
				)
			)
		)
		(zone
			(layer "B.Cu")
			(hatch none 0.5)
			(connect_pads
				(clearance 0)
			)
			(min_thickness 0.25)
			(keepout
				(tracks not_allowed)
				(vias allowed)
				(pads allowed)
				(copperpour not_allowed)
				(footprints allowed)
			)
			(placement
				(enabled no)
				(sheetname "")
			)
			(fill
				(thermal_gap 0.5)
				(thermal_bridge_width 0.5)
				(island_removal_mode 0)
			)
			(polygon
				(pts
					(xy 197.493128 -79.169006) (xy 197.493128 -78.661006) (xy 197.874128 -78.661006) (xy 197.874128 -79.169006)
				)
			)
		)
	)
	(footprint ""
		(layer "B.Cu")
		(at 176.022 -88.646 180)
		(property "Reference" "R6N9"
			(at 0 0 0)
			(layer "B.SilkS")
			(hide yes)
			(effects
				(font
					(size 1.27 1.27)
				)
				(justify mirror)
			)
		)
		(property "Value" ""
			(at 0 0 0)
			(layer "B.Fab")
			(effects
				(font
					(size 1.27 1.27)
				)
				(justify mirror)
			)
		)
		(duplicate_pad_numbers_are_jumpers no)
		(fp_poly
			(pts
				(xy 0.2794 -0.1016) (xy -0.2794 -0.1016) (xy -0.2794 0.9906) (xy 0.2794 0.9906)
			)
			(stroke
				(width 0)
				(type default)
			)
			(fill no)
			(layer "B.CrtYd")
		)
		(fp_line
			(start 0.2794 0.9906)
			(end -0.2794 0.9906)
			(stroke
				(width 0.1)
				(type default)
			)
			(layer "B.Fab")
		)
		(fp_line
			(start 0.2794 -0.1016)
			(end 0.2794 0.9906)
			(stroke
				(width 0.1)
				(type default)
			)
			(layer "B.Fab")
		)
		(fp_line
			(start -0.2794 0.9906)
			(end -0.2794 -0.1016)
			(stroke
				(width 0.1)
				(type default)
			)
			(layer "B.Fab")
		)
		(fp_line
			(start -0.2794 -0.1016)
			(end 0.2794 -0.1016)
			(stroke
				(width 0.1)
				(type default)
			)
			(layer "B.Fab")
		)
		(pad "1" smd rect
			(at 0 0)
			(size 0.508 0.508)
			(layers "B.Cu" "B.Mask" "B.Paste")
			(net "SMB_CPU1_PE_HP_GTL_SDA")
		)
		(pad "2" smd rect
			(at 0 0.889)
			(size 0.508 0.508)
			(layers "B.Cu" "B.Mask" "B.Paste")
			(net "SMB_CPU1_PE_HP_GTL_R_SDA")
		)
		(zone
			(layer "B.Cu")
			(hatch none 0.5)
			(connect_pads
				(clearance 0)
			)
			(min_thickness 0.25)
			(keepout
				(tracks not_allowed)
				(vias allowed)
				(pads allowed)
				(copperpour not_allowed)
				(footprints allowed)
			)
			(placement
				(enabled no)
				(sheetname "")
			)
			(fill
				(thermal_gap 0.5)
				(thermal_bridge_width 0.5)
				(island_removal_mode 0)
			)
			(polygon
				(pts
					(xy 175.768 -89.281) (xy 176.276 -89.281) (xy 176.276 -88.9) (xy 175.768 -88.9)
				)
			)
		)
		(zone
			(layer "B.Cu")
			(hatch none 0.5)
			(connect_pads
				(clearance 0)
			)
			(min_thickness 0.25)
			(keepout
				(tracks allowed)
				(vias not_allowed)
				(pads allowed)
				(copperpour not_allowed)
				(footprints allowed)
			)
			(placement
				(enabled no)
				(sheetname "")
			)
			(fill
				(thermal_gap 0.5)
				(thermal_bridge_width 0.5)
				(island_removal_mode 0)
			)
			(polygon
				(pts
					(xy 175.768 -88.9) (xy 176.276 -88.9) (xy 176.276 -89.281) (xy 175.768 -89.281)
				)
			)
		)
	)
	(footprint ""
		(layer "B.Cu")
		(at 400.177 -108.077 180)
		(property "Reference" "C2N10"
			(at 0 0 0)
			(layer "B.SilkS")
			(hide yes)
			(effects
				(font
					(size 1.27 1.27)
				)
				(justify mirror)
			)
		)
		(property "Value" ""
			(at 0 0 0)
			(layer "B.Fab")
			(effects
				(font
					(size 1.27 1.27)
				)
				(justify mirror)
			)
		)
		(duplicate_pad_numbers_are_jumpers no)
		(fp_poly
			(pts
				(xy 0.4953 -0.2032) (xy -0.4953 -0.2032) (xy -0.4953 1.6002) (xy 0.4953 1.6002)
			)
			(stroke
				(width 0)
				(type default)
			)
			(fill no)
			(layer "B.CrtYd")
		)
		(fp_line
			(start 0.4953 1.6002)
			(end 0.4953 -0.2032)
			(stroke
				(width 0.1)
				(type default)
			)
			(layer "B.Fab")
		)
		(fp_line
			(start 0.4953 -0.2032)
			(end -0.4953 -0.2032)
			(stroke
				(width 0.1)
				(type default)
			)
			(layer "B.Fab")
		)
		(fp_line
			(start -0.4953 1.6002)
			(end 0.4953 1.6002)
			(stroke
				(width 0.1)
				(type default)
			)
			(layer "B.Fab")
		)
		(fp_line
			(start -0.4953 -0.2032)
			(end -0.4953 1.6002)
			(stroke
				(width 0.1)
				(type default)
			)
			(layer "B.Fab")
		)
		(pad "1" smd rect
			(at 0 0)
			(size 0.762 0.889)
			(layers "B.Cu" "B.Mask" "B.Paste")
			(net "P1V05_PCH_STBY")
		)
		(pad "2" smd rect
			(at 0 1.397)
			(size 0.762 0.889)
			(layers "B.Cu" "B.Mask" "B.Paste")
			(net "GND")
		)
		(zone
			(layer "B.Cu")
			(hatch none 0.5)
			(connect_pads
				(clearance 0)
			)
			(min_thickness 0.25)
			(keepout
				(tracks not_allowed)
				(vias allowed)
				(pads allowed)
				(copperpour not_allowed)
				(footprints allowed)
			)
			(placement
				(enabled no)
				(sheetname "")
			)
			(fill
				(thermal_gap 0.5)
				(thermal_bridge_width 0.5)
				(island_removal_mode 0)
			)
			(polygon
				(pts
					(xy 399.796 -108.5215) (xy 400.558 -108.5215) (xy 400.558 -109.0295) (xy 399.796 -109.0295)
				)
			)
		)
	)
	(footprint ""
		(layer "B.Cu")
		(at 83.856068 -12.954 -90)
		(property "Reference" "C5G80"
			(at -1.14681 0.76708 0)
			(unlocked yes)
			(layer "B.SilkS")
			(effects
				(font
					(size 0.7874 0.5842)
					(thickness 0.1524)
				)
				(justify mirror)
			)
		)
		(property "Value" ""
			(at 0 0 90)
			(layer "B.Fab")
			(effects
				(font
					(size 1.27 1.27)
				)
				(justify mirror)
			)
		)
		(duplicate_pad_numbers_are_jumpers no)
		(fp_rect
			(start 0.4953 1.6002)
			(end -0.4953 -0.2032)
			(stroke
				(width 0)
				(type default)
			)
			(fill no)
			(layer "B.CrtYd")
		)
		(fp_line
			(start -0.4953 1.6002)
			(end 0.4953 1.6002)
			(stroke
				(width 0.1)
				(type default)
			)
			(layer "B.Fab")
		)
		(fp_line
			(start 0.4953 1.6002)
			(end 0.4953 -0.2032)
			(stroke
				(width 0.1)
				(type default)
			)
			(layer "B.Fab")
		)
		(fp_line
			(start -0.4953 -0.2032)
			(end -0.4953 1.6002)
			(stroke
				(width 0.1)
				(type default)
			)
			(layer "B.Fab")
		)
		(fp_line
			(start 0.4953 -0.2032)
			(end -0.4953 -0.2032)
			(stroke
				(width 0.1)
				(type default)
			)
			(layer "B.Fab")
		)
		(pad "1" smd rect
			(at 0 0 90)
			(size 0.762 0.889)
			(layers "B.Cu" "B.Mask" "B.Paste")
			(net "PVDDQ_GHJ")
		)
		(pad "2" smd rect
			(at 0 1.397 90)
			(size 0.762 0.889)
			(layers "B.Cu" "B.Mask" "B.Paste")
			(net "GND")
		)
		(zone
			(layer "B.Cu")
			(hatch none 0.5)
			(connect_pads
				(clearance 0)
			)
			(min_thickness 0.25)
			(keepout
				(tracks not_allowed)
				(vias allowed)
				(pads allowed)
				(copperpour not_allowed)
				(footprints allowed)
			)
			(placement
				(enabled no)
				(sheetname "")
			)
			(fill
				(thermal_gap 0.5)
				(thermal_bridge_width 0.5)
				(island_removal_mode 0)
			)
			(polygon
				(pts
					(xy 82.903568 -12.573) (xy 83.411568 -12.573) (xy 83.411568 -13.335) (xy 82.903568 -13.335)
				)
			)
		)
	)
	(footprint ""
		(layer "B.Cu")
		(at 489.65739 -145.288 90)
		(property "Reference" "R1L20"
			(at 0 0 90)
			(layer "B.SilkS")
			(hide yes)
			(effects
				(font
					(size 1.27 1.27)
				)
				(justify mirror)
			)
		)
		(property "Value" ""
			(at 0 0 90)
			(layer "B.Fab")
			(effects
				(font
					(size 1.27 1.27)
				)
				(justify mirror)
			)
		)
		(duplicate_pad_numbers_are_jumpers no)
		(fp_poly
			(pts
				(xy 0.2794 -0.1016) (xy -0.2794 -0.1016) (xy -0.2794 0.9906) (xy 0.2794 0.9906)
			)
			(stroke
				(width 0)
				(type default)
			)
			(fill no)
			(layer "B.CrtYd")
		)
		(fp_line
			(start 0.2794 -0.1016)
			(end 0.2794 0.9906)
			(stroke
				(width 0.1)
				(type default)
			)
			(layer "B.Fab")
		)
		(fp_line
			(start -0.2794 -0.1016)
			(end 0.2794 -0.1016)
			(stroke
				(width 0.1)
				(type default)
			)
			(layer "B.Fab")
		)
		(fp_line
			(start 0.2794 0.9906)
			(end -0.2794 0.9906)
			(stroke
				(width 0.1)
				(type default)
			)
			(layer "B.Fab")
		)
		(fp_line
			(start -0.2794 0.9906)
			(end -0.2794 -0.1016)
			(stroke
				(width 0.1)
				(type default)
			)
			(layer "B.Fab")
		)
		(pad "1" smd rect
			(at 0 0 270)
			(size 0.508 0.508)
			(layers "B.Cu" "B.Mask" "B.Paste")
			(net "LED_POSTCODE_4")
		)
		(pad "2" smd rect
			(at 0 0.889 270)
			(size 0.508 0.508)
			(layers "B.Cu" "B.Mask" "B.Paste")
			(net "LED_POSTCODE_4_R")
		)
		(zone
			(layer "B.Cu")
			(hatch none 0.5)
			(connect_pads
				(clearance 0)
			)
			(min_thickness 0.25)
			(keepout
				(tracks allowed)
				(vias not_allowed)
				(pads allowed)
				(copperpour not_allowed)
				(footprints allowed)
			)
			(placement
				(enabled no)
				(sheetname "")
			)
			(fill
				(thermal_gap 0.5)
				(thermal_bridge_width 0.5)
				(island_removal_mode 0)
			)
			(polygon
				(pts
					(xy 489.91139 -145.542) (xy 489.91139 -145.034) (xy 490.29239 -145.034) (xy 490.29239 -145.542)
				)
			)
		)
		(zone
			(layer "B.Cu")
			(hatch none 0.5)
			(connect_pads
				(clearance 0)
			)
			(min_thickness 0.25)
			(keepout
				(tracks not_allowed)
				(vias allowed)
				(pads allowed)
				(copperpour not_allowed)
				(footprints allowed)
			)
			(placement
				(enabled no)
				(sheetname "")
			)
			(fill
				(thermal_gap 0.5)
				(thermal_bridge_width 0.5)
				(island_removal_mode 0)
			)
			(polygon
				(pts
					(xy 490.29239 -145.542) (xy 490.29239 -145.034) (xy 489.91139 -145.034) (xy 489.91139 -145.542)
				)
			)
		)
	)
)
